G04*
G04 #@! TF.GenerationSoftware,Altium Limited,Altium Designer,23.0.1 (38)*
G04*
G04 Layer_Physical_Order=4*
G04 Layer_Color=16711680*
%FSLAX44Y44*%
%MOMM*%
G71*
G04*
G04 #@! TF.SameCoordinates,9A23C038-B079-480F-8166-AFFB5740F5AE*
G04*
G04*
G04 #@! TF.FilePolarity,Positive*
G04*
G01*
G75*
%ADD44C,0.2540*%
%ADD46C,0.5500*%
%ADD47C,0.5588*%
G36*
X662899Y313154D02*
X664122Y312648D01*
X665223Y311913D01*
X666159Y310977D01*
X666895Y309878D01*
X667402Y308655D01*
X667661Y307358D01*
X667662Y306697D01*
X667632Y10150D01*
X667632Y10150D01*
X667632Y10150D01*
X667632Y9548D01*
X667397Y8368D01*
X666937Y7257D01*
X666269Y6256D01*
X665419Y5405D01*
X664419Y4736D01*
X663307Y4275D01*
X662128Y4039D01*
X661526Y4038D01*
X10450Y4078D01*
X10450Y4078D01*
X10450Y4078D01*
X9822D01*
X8591Y4323D01*
X7432Y4803D01*
X6388Y5501D01*
X5501Y6388D01*
X4803Y7432D01*
X4323Y8591D01*
X4078Y9822D01*
X4078Y10450D01*
X4078Y10450D01*
X4078Y10450D01*
X4058Y306760D01*
D01*
X4058Y307413D01*
X4313Y308693D01*
X4812Y309900D01*
X5537Y310985D01*
X6460Y311909D01*
X7545Y312635D01*
X8751Y313135D01*
X10031Y313391D01*
X10684Y313392D01*
D01*
X660940Y313412D01*
X661602D01*
X662899Y313154D01*
D02*
G37*
%LPC*%
G36*
X635037Y308538D02*
X631983D01*
X631589Y308460D01*
X631188D01*
X628193Y307864D01*
X627822Y307711D01*
X627428Y307632D01*
X624607Y306464D01*
X624273Y306241D01*
X623902Y306087D01*
X621363Y304391D01*
X621079Y304107D01*
X620746Y303883D01*
X618587Y301724D01*
X618363Y301390D01*
X618079Y301106D01*
X616383Y298568D01*
X616229Y298197D01*
X616006Y297863D01*
X614838Y295042D01*
X614759Y294648D01*
X614606Y294277D01*
X614010Y291282D01*
Y290881D01*
X613932Y290487D01*
Y288960D01*
Y287433D01*
X614010Y287039D01*
Y286638D01*
X614606Y283643D01*
X614759Y283272D01*
X614838Y282878D01*
X616006Y280057D01*
X616229Y279723D01*
X616383Y279352D01*
X618079Y276814D01*
X618363Y276529D01*
X618587Y276196D01*
X620746Y274037D01*
X621079Y273813D01*
X621363Y273529D01*
X623902Y271833D01*
X624273Y271679D01*
X624607Y271456D01*
X627428Y270288D01*
X627822Y270209D01*
X628193Y270056D01*
X631188Y269460D01*
X631589D01*
X631983Y269382D01*
X635037D01*
X635431Y269460D01*
X635832D01*
X638827Y270056D01*
X639198Y270209D01*
X639592Y270288D01*
X642413Y271456D01*
X642747Y271679D01*
X643118Y271833D01*
X645657Y273529D01*
X645941Y273813D01*
X646274Y274037D01*
X648434Y276196D01*
X648657Y276530D01*
X648941Y276814D01*
X650637Y279352D01*
X650791Y279723D01*
X651014Y280057D01*
X652182Y282878D01*
X652261Y283272D01*
X652414Y283643D01*
X653010Y286638D01*
Y287039D01*
X653088Y287433D01*
Y288960D01*
Y290487D01*
X653010Y290881D01*
Y291282D01*
X652414Y294277D01*
X652261Y294648D01*
X652182Y295042D01*
X651014Y297863D01*
X650791Y298197D01*
X650637Y298568D01*
X648941Y301106D01*
X648657Y301391D01*
X648434Y301724D01*
X646274Y303883D01*
X645940Y304107D01*
X645657Y304391D01*
X643118Y306087D01*
X642747Y306241D01*
X642413Y306464D01*
X639592Y307632D01*
X639198Y307711D01*
X638827Y307864D01*
X635832Y308460D01*
X635431D01*
X635037Y308538D01*
D02*
G37*
G36*
X30037D02*
X26983D01*
X26589Y308460D01*
X26188D01*
X23193Y307864D01*
X22822Y307711D01*
X22428Y307632D01*
X19607Y306464D01*
X19273Y306241D01*
X18902Y306087D01*
X16364Y304391D01*
X16079Y304107D01*
X15746Y303883D01*
X13586Y301724D01*
X13363Y301390D01*
X13079Y301106D01*
X11383Y298568D01*
X11229Y298197D01*
X11006Y297863D01*
X9838Y295042D01*
X9759Y294648D01*
X9606Y294277D01*
X9010Y291282D01*
Y290881D01*
X8932Y290487D01*
Y288960D01*
Y287433D01*
X9010Y287039D01*
Y286638D01*
X9606Y283643D01*
X9759Y283272D01*
X9838Y282878D01*
X11006Y280057D01*
X11229Y279723D01*
X11383Y279352D01*
X13079Y276814D01*
X13363Y276529D01*
X13586Y276196D01*
X15746Y274037D01*
X16079Y273813D01*
X16364Y273529D01*
X18902Y271833D01*
X19273Y271679D01*
X19607Y271456D01*
X22428Y270288D01*
X22822Y270209D01*
X23193Y270056D01*
X26188Y269460D01*
X26589D01*
X26983Y269382D01*
X30037D01*
X30431Y269460D01*
X30832D01*
X33827Y270056D01*
X34198Y270209D01*
X34592Y270288D01*
X37413Y271456D01*
X37747Y271679D01*
X38118Y271833D01*
X40656Y273529D01*
X40941Y273813D01*
X41274Y274037D01*
X43433Y276196D01*
X43657Y276530D01*
X43941Y276814D01*
X45637Y279352D01*
X45791Y279723D01*
X46014Y280057D01*
X47182Y282878D01*
X47261Y283272D01*
X47414Y283643D01*
X48010Y286638D01*
Y287039D01*
X48088Y287433D01*
Y288960D01*
Y290487D01*
X48010Y290881D01*
Y291282D01*
X47414Y294277D01*
X47261Y294648D01*
X47182Y295042D01*
X46014Y297863D01*
X45791Y298197D01*
X45637Y298568D01*
X43941Y301106D01*
X43657Y301391D01*
X43433Y301724D01*
X41274Y303883D01*
X40940Y304107D01*
X40656Y304391D01*
X38118Y306087D01*
X37747Y306241D01*
X37413Y306464D01*
X34592Y307632D01*
X34198Y307711D01*
X33827Y307864D01*
X30832Y308460D01*
X30431D01*
X30037Y308538D01*
D02*
G37*
G36*
X523910Y246750D02*
X522020D01*
X520274Y246027D01*
X518938Y244691D01*
X518215Y242945D01*
Y241055D01*
X518938Y239309D01*
X519649Y238599D01*
Y211405D01*
X518973Y210730D01*
X518250Y208984D01*
Y207094D01*
X518973Y205349D01*
X520309Y204013D01*
X522055Y203289D01*
X523945D01*
X525691Y204013D01*
X527027Y205349D01*
X527750Y207094D01*
Y208984D01*
X527027Y210730D01*
X526317Y211440D01*
Y238634D01*
X526992Y239309D01*
X527715Y241055D01*
Y242945D01*
X526992Y244691D01*
X525656Y246027D01*
X523910Y246750D01*
D02*
G37*
G36*
X536945Y237441D02*
X535055D01*
X533309Y236717D01*
X531973Y235381D01*
X531250Y233636D01*
Y231746D01*
X531973Y230000D01*
X532666Y229307D01*
Y211383D01*
X531973Y210691D01*
X531250Y208945D01*
Y207055D01*
X531973Y205309D01*
X533309Y203973D01*
X535055Y203250D01*
X536945D01*
X538691Y203973D01*
X540027Y205309D01*
X540750Y207055D01*
Y208945D01*
X540027Y210691D01*
X539334Y211383D01*
Y229307D01*
X540027Y230000D01*
X540750Y231746D01*
Y233636D01*
X540027Y235381D01*
X538691Y236717D01*
X536945Y237441D01*
D02*
G37*
G36*
X561945Y127750D02*
X560055D01*
X558309Y127027D01*
X556973Y125691D01*
X556250Y123945D01*
Y122055D01*
X556973Y120309D01*
X558309Y118973D01*
X560055Y118250D01*
X561945D01*
X563691Y118973D01*
X565027Y120309D01*
X565750Y122055D01*
Y123945D01*
X565027Y125691D01*
X563691Y127027D01*
X561945Y127750D01*
D02*
G37*
G36*
Y107750D02*
X560055D01*
X558309Y107027D01*
X556973Y105691D01*
X556250Y103945D01*
Y102055D01*
X556973Y100309D01*
X558309Y98973D01*
X560055Y98250D01*
X561945D01*
X563691Y98973D01*
X565027Y100309D01*
X565750Y102055D01*
Y103945D01*
X565027Y105691D01*
X563691Y107027D01*
X561945Y107750D01*
D02*
G37*
G36*
X635037Y48538D02*
X631983D01*
X631589Y48460D01*
X631188D01*
X628193Y47864D01*
X627822Y47711D01*
X627428Y47632D01*
X624607Y46464D01*
X624273Y46241D01*
X623902Y46087D01*
X621363Y44391D01*
X621079Y44107D01*
X620746Y43884D01*
X618587Y41725D01*
X618363Y41391D01*
X618079Y41107D01*
X616383Y38568D01*
X616229Y38197D01*
X616006Y37863D01*
X614838Y35042D01*
X614759Y34648D01*
X614606Y34277D01*
X614010Y31282D01*
Y30881D01*
X613932Y30487D01*
Y28960D01*
Y27433D01*
X614010Y27039D01*
Y26638D01*
X614606Y23643D01*
X614759Y23272D01*
X614838Y22878D01*
X616006Y20057D01*
X616229Y19723D01*
X616383Y19352D01*
X618079Y16813D01*
X618363Y16529D01*
X618587Y16195D01*
X620746Y14037D01*
X621079Y13813D01*
X621363Y13529D01*
X623902Y11833D01*
X624273Y11679D01*
X624607Y11456D01*
X627428Y10288D01*
X627822Y10209D01*
X628193Y10056D01*
X631188Y9460D01*
X631589D01*
X631983Y9382D01*
X635037D01*
X635431Y9460D01*
X635832D01*
X638827Y10056D01*
X639198Y10209D01*
X639592Y10288D01*
X642413Y11456D01*
X642747Y11679D01*
X643118Y11833D01*
X645657Y13529D01*
X645941Y13813D01*
X646274Y14037D01*
X648434Y16195D01*
X648657Y16530D01*
X648941Y16813D01*
X650637Y19352D01*
X650791Y19723D01*
X651014Y20057D01*
X652182Y22878D01*
X652261Y23272D01*
X652414Y23643D01*
X653010Y26638D01*
Y27039D01*
X653088Y27433D01*
Y28960D01*
Y30487D01*
X653010Y30881D01*
Y31282D01*
X652414Y34277D01*
X652261Y34648D01*
X652182Y35042D01*
X651014Y37863D01*
X650791Y38197D01*
X650637Y38568D01*
X648941Y41107D01*
X648657Y41391D01*
X648434Y41725D01*
X646274Y43884D01*
X645940Y44107D01*
X645657Y44391D01*
X643118Y46087D01*
X642747Y46241D01*
X642413Y46464D01*
X639592Y47632D01*
X639198Y47711D01*
X638827Y47864D01*
X635832Y48460D01*
X635431D01*
X635037Y48538D01*
D02*
G37*
G36*
X30037D02*
X26983D01*
X26589Y48460D01*
X26188D01*
X23193Y47864D01*
X22822Y47711D01*
X22428Y47632D01*
X19607Y46464D01*
X19273Y46241D01*
X18902Y46087D01*
X16364Y44391D01*
X16079Y44107D01*
X15746Y43884D01*
X13586Y41725D01*
X13363Y41391D01*
X13079Y41107D01*
X11383Y38568D01*
X11229Y38197D01*
X11006Y37863D01*
X9838Y35042D01*
X9759Y34648D01*
X9606Y34277D01*
X9010Y31282D01*
Y30881D01*
X8932Y30487D01*
Y28960D01*
Y27433D01*
X9010Y27039D01*
Y26638D01*
X9606Y23643D01*
X9759Y23272D01*
X9838Y22878D01*
X11006Y20057D01*
X11229Y19723D01*
X11383Y19352D01*
X13079Y16813D01*
X13363Y16529D01*
X13586Y16195D01*
X15746Y14037D01*
X16079Y13813D01*
X16364Y13529D01*
X18902Y11833D01*
X19273Y11679D01*
X19607Y11456D01*
X22428Y10288D01*
X22822Y10209D01*
X23193Y10056D01*
X26188Y9460D01*
X26589D01*
X26983Y9382D01*
X30037D01*
X30431Y9460D01*
X30832D01*
X33827Y10056D01*
X34198Y10209D01*
X34592Y10288D01*
X37413Y11456D01*
X37747Y11679D01*
X38118Y11833D01*
X40656Y13529D01*
X40941Y13813D01*
X41274Y14037D01*
X43433Y16195D01*
X43657Y16530D01*
X43941Y16813D01*
X45637Y19352D01*
X45791Y19723D01*
X46014Y20057D01*
X47182Y22878D01*
X47261Y23272D01*
X47414Y23643D01*
X48010Y26638D01*
Y27039D01*
X48088Y27433D01*
Y28960D01*
Y30487D01*
X48010Y30881D01*
Y31282D01*
X47414Y34277D01*
X47261Y34648D01*
X47182Y35042D01*
X46014Y37863D01*
X45791Y38197D01*
X45637Y38568D01*
X43941Y41107D01*
X43657Y41391D01*
X43433Y41725D01*
X41274Y43884D01*
X40940Y44107D01*
X40656Y44391D01*
X38118Y46087D01*
X37747Y46241D01*
X37413Y46464D01*
X34592Y47632D01*
X34198Y47711D01*
X33827Y47864D01*
X30832Y48460D01*
X30431D01*
X30037Y48538D01*
D02*
G37*
%LPD*%
D44*
X522982Y208057D02*
Y241982D01*
Y208057D02*
X523000Y208039D01*
X522965Y242000D02*
X522982Y241982D01*
X536000Y208000D02*
Y232691D01*
D46*
X523000Y208039D02*
D03*
X522965Y242000D02*
D03*
X536000Y232691D02*
D03*
X241871Y254805D02*
D03*
X231291D02*
D03*
X220711D02*
D03*
X210131D02*
D03*
X199634Y253481D02*
D03*
X190160Y248771D02*
D03*
X182390Y241591D02*
D03*
X174908Y234110D02*
D03*
X167427Y226629D02*
D03*
X159946Y219147D02*
D03*
X152465Y211666D02*
D03*
X144033Y205276D02*
D03*
X133555Y203805D02*
D03*
X122976D02*
D03*
X112410Y204354D02*
D03*
X101844Y203805D02*
D03*
X91264D02*
D03*
X80684D02*
D03*
X70105Y203927D02*
D03*
X62147Y210899D02*
D03*
X51602Y210033D02*
D03*
X44897Y201849D02*
D03*
X46109Y191339D02*
D03*
X54498Y184892D02*
D03*
X64966Y186424D02*
D03*
X73834Y192195D02*
D03*
X84414D02*
D03*
X94994D02*
D03*
X116052D02*
D03*
X126632D02*
D03*
X137212Y192229D02*
D03*
X147587Y194300D02*
D03*
X156682Y199706D02*
D03*
X164283Y207065D02*
D03*
X171765Y214546D02*
D03*
X179246Y222027D02*
D03*
X186727Y229508D02*
D03*
X194208Y236989D02*
D03*
X203283Y242429D02*
D03*
X213835Y243195D02*
D03*
X224415D02*
D03*
X234995D02*
D03*
X255209Y245785D02*
D03*
X252362Y255974D02*
D03*
X536000Y208000D02*
D03*
X561000Y103000D02*
D03*
Y123000D02*
D03*
X560000Y143000D02*
D03*
D47*
X175640Y128600D02*
D03*
X124840Y154000D02*
D03*
X150240Y103200D02*
D03*
X404029Y103411D02*
D03*
X455040Y128600D02*
D03*
X429640D02*
D03*
X404240D02*
D03*
X302640Y230200D02*
D03*
X632840Y255600D02*
D03*
Y230200D02*
D03*
Y204800D02*
D03*
Y154000D02*
D03*
Y52400D02*
D03*
X607440Y281000D02*
D03*
Y255600D02*
D03*
Y230200D02*
D03*
Y179400D02*
D03*
Y52400D02*
D03*
Y27000D02*
D03*
X582040Y281000D02*
D03*
Y255600D02*
D03*
Y154000D02*
D03*
Y52400D02*
D03*
X556640Y281000D02*
D03*
Y255600D02*
D03*
Y204800D02*
D03*
Y179400D02*
D03*
Y154000D02*
D03*
Y52400D02*
D03*
X531240Y281000D02*
D03*
Y255600D02*
D03*
Y52400D02*
D03*
X505840Y281000D02*
D03*
Y204800D02*
D03*
Y179400D02*
D03*
Y154000D02*
D03*
Y128600D02*
D03*
Y52400D02*
D03*
X480440Y281000D02*
D03*
Y255600D02*
D03*
Y204800D02*
D03*
Y179400D02*
D03*
Y154000D02*
D03*
Y128600D02*
D03*
Y103200D02*
D03*
Y52400D02*
D03*
X455040Y281000D02*
D03*
Y255600D02*
D03*
Y179400D02*
D03*
Y154000D02*
D03*
Y52400D02*
D03*
X429640Y281000D02*
D03*
Y255600D02*
D03*
Y230200D02*
D03*
Y154000D02*
D03*
Y103200D02*
D03*
Y77800D02*
D03*
Y52400D02*
D03*
X404240Y281000D02*
D03*
Y255600D02*
D03*
Y230200D02*
D03*
Y204800D02*
D03*
Y77800D02*
D03*
Y52400D02*
D03*
X378840Y281000D02*
D03*
Y179400D02*
D03*
Y52400D02*
D03*
X353440Y281000D02*
D03*
Y255600D02*
D03*
Y179400D02*
D03*
Y154000D02*
D03*
Y52400D02*
D03*
X328040Y281000D02*
D03*
Y179400D02*
D03*
Y154000D02*
D03*
Y128600D02*
D03*
Y52400D02*
D03*
X302640Y281000D02*
D03*
Y179400D02*
D03*
Y154000D02*
D03*
Y128600D02*
D03*
Y52400D02*
D03*
X277240Y281000D02*
D03*
Y179400D02*
D03*
Y154000D02*
D03*
Y128600D02*
D03*
Y77800D02*
D03*
Y52400D02*
D03*
X251840Y281000D02*
D03*
Y179400D02*
D03*
Y154000D02*
D03*
Y128600D02*
D03*
Y52400D02*
D03*
X226440Y281000D02*
D03*
Y230200D02*
D03*
Y204800D02*
D03*
Y179400D02*
D03*
Y154000D02*
D03*
Y128600D02*
D03*
Y103200D02*
D03*
Y27000D02*
D03*
X201040Y281000D02*
D03*
Y230200D02*
D03*
Y204800D02*
D03*
Y179400D02*
D03*
Y154000D02*
D03*
Y128600D02*
D03*
Y103200D02*
D03*
Y52400D02*
D03*
Y27000D02*
D03*
X175640Y281000D02*
D03*
Y255600D02*
D03*
Y204800D02*
D03*
Y179400D02*
D03*
Y154000D02*
D03*
Y77800D02*
D03*
Y52400D02*
D03*
Y27000D02*
D03*
X150240Y281000D02*
D03*
Y255600D02*
D03*
Y230200D02*
D03*
Y179400D02*
D03*
Y154000D02*
D03*
Y77800D02*
D03*
Y52400D02*
D03*
Y27000D02*
D03*
X124840Y281000D02*
D03*
Y255600D02*
D03*
Y230200D02*
D03*
Y77800D02*
D03*
Y52400D02*
D03*
Y27000D02*
D03*
X99440Y281000D02*
D03*
Y255600D02*
D03*
Y154000D02*
D03*
Y77800D02*
D03*
Y52400D02*
D03*
Y27000D02*
D03*
X74040Y281000D02*
D03*
Y255600D02*
D03*
Y230200D02*
D03*
Y179400D02*
D03*
Y154000D02*
D03*
Y128600D02*
D03*
Y103200D02*
D03*
Y77800D02*
D03*
Y52400D02*
D03*
Y27000D02*
D03*
X48640Y255600D02*
D03*
Y154000D02*
D03*
Y128600D02*
D03*
Y103200D02*
D03*
Y77800D02*
D03*
Y52400D02*
D03*
X23240Y255600D02*
D03*
Y154000D02*
D03*
Y128600D02*
D03*
Y103200D02*
D03*
Y77800D02*
D03*
Y52400D02*
D03*
M02*
